(kicad_pcb
	(version 20260206)
	(generator "pcbnew")
	(generator_version "10.0")
	(general
		(thickness 1.6)
		(legacy_teardrops no)
	)
	(paper "A4")
	(title_block
		(title "Bryce Canyon_SCC_16316-1_OCP.brd")
		(comment 1 "Bryce Canyon / footprints 1174-1181 of 1561")
	)
	(layers
		(0 "F.Cu" signal "TOP")
		(4 "In1.Cu" signal "L2GND")
		(6 "In2.Cu" signal "L3")
		(8 "In3.Cu" signal "L4VCC")
		(10 "In4.Cu" signal "L5VCC")
		(12 "In5.Cu" signal "L6")
		(14 "In6.Cu" signal "L7GND")
		(2 "B.Cu" signal "BOTTOM")
		(9 "F.Adhes" user "F.Adhesive")
		(11 "B.Adhes" user "B.Adhesive")
		(13 "F.Paste" user "Package Geometry/Pastemask Top")
		(15 "B.Paste" user "Package Geometry/Pastemask Bottom")
		(5 "F.SilkS" user "Ref Des/Silkscreen Top")
		(7 "B.SilkS" user "Ref Des/Silkscreen Bottom")
		(1 "F.Mask" user "Board Geometry/Soldermask Top")
		(3 "B.Mask" user "Board Geometry/Soldermask Bottom")
		(17 "Dwgs.User" user "User.Drawings")
		(19 "Cmts.User" user "User.Comments")
		(21 "Eco1.User" user "User.Eco1")
		(23 "Eco2.User" user "User.Eco2")
		(25 "Edge.Cuts" user "Board Geometry/Outline")
		(27 "Margin" user)
		(31 "F.CrtYd" user "Package Geometry/Place Bound Top")
		(29 "B.CrtYd" user "Package Geometry/Place Bound Bottom")
		(35 "F.Fab" user "Ref Des/Assembly Top")
		(33 "B.Fab" user "Ref Des/Assembly Bottom")
	)
	(footprint ""
		(layer "B.Cu")
		(at 163.75634 -6.240018 180)
		(property "Reference" "R578"
			(at 0 0 0)
			(layer "B.SilkS")
			(hide yes)
			(effects
				(font
					(size 1.27 1.27)
				)
				(justify mirror)
			)
		)
		(property "Value" "0R2J-2-GP"
			(at -0.064008 -3.993896 180)
			(unlocked yes)
			(layer "B.Fab")
			(hide yes)
			(effects
				(font
					(size 1.016 1.016)
					(thickness 0.1524)
				)
				(justify mirror)
			)
		)
		(property "Device Type" "R402H16"
			(at -0.064008 -5.517896 180)
			(unlocked yes)
			(layer "B.Fab")
			(hide yes)
			(effects
				(font
					(size 1.016 1.016)
					(thickness 0.1524)
				)
				(justify mirror)
			)
		)
		(duplicate_pad_numbers_are_jumpers no)
		(fp_line
			(start 0.508 -0.9398)
			(end 0.508 0.9398)
			(stroke
				(width 0.1524)
				(type default)
			)
			(layer "B.SilkS")
		)
		(fp_line
			(start -0.508 -0.9398)
			(end 0.508 -0.9398)
			(stroke
				(width 0.1524)
				(type default)
			)
			(layer "B.SilkS")
		)
		(fp_rect
			(start 0.508 0.9398)
			(end -0.508 -0.9398)
			(stroke
				(width 0)
				(type default)
			)
			(fill no)
			(layer "B.CrtYd")
		)
		(fp_rect
			(start 0.508 0.9398)
			(end -0.508 -0.9398)
			(stroke
				(width 0)
				(type default)
			)
			(fill no)
			(layer "B.Fab")
		)
		(pad "1" smd custom
			(at 0 -0.4445)
			(size 0.1397 0.1397)
			(layers "B.Cu" "B.Mask" "B.Paste")
			(net "SCC_RESET_N")
			(options
				(clearance outline)
				(anchor circle)
			)
			(primitives
				(gr_poly
					(pts
						(arc
							(start -0.1778 0.2794)
							(mid -0.249642 0.249642)
							(end -0.2794 0.1778)
						)
						(arc
							(start -0.2794 -0.1778)
							(mid -0.249642 -0.249642)
							(end -0.1778 -0.2794)
						)
						(arc
							(start 0.1778 -0.2794)
							(mid 0.249642 -0.249642)
							(end 0.2794 -0.1778)
						)
						(arc
							(start 0.2794 0.1778)
							(mid 0.249642 0.249642)
							(end 0.1778 0.2794)
						)
					)
					(width 0)
					(fill yes)
				)
			)
		)
		(pad "2" smd custom
			(at 0 0.4445)
			(size 0.1397 0.1397)
			(layers "B.Cu" "B.Mask" "B.Paste")
			(net "SCC_RESET_BUF_N")
			(options
				(clearance outline)
				(anchor circle)
			)
			(primitives
				(gr_poly
					(pts
						(arc
							(start -0.1778 0.2794)
							(mid -0.249642 0.249642)
							(end -0.2794 0.1778)
						)
						(arc
							(start -0.2794 -0.1778)
							(mid -0.249642 -0.249642)
							(end -0.1778 -0.2794)
						)
						(arc
							(start 0.1778 -0.2794)
							(mid 0.249642 -0.249642)
							(end 0.2794 -0.1778)
						)
						(arc
							(start 0.2794 0.1778)
							(mid 0.249642 0.249642)
							(end 0.1778 0.2794)
						)
					)
					(width 0)
					(fill yes)
				)
			)
		)
	)
	(footprint ""
		(layer "B.Cu")
		(at 137.4648 -66.8274 -90)
		(property "Reference" "C19"
			(at 0 0 90)
			(layer "B.SilkS")
			(hide yes)
			(effects
				(font
					(size 1.27 1.27)
				)
				(justify mirror)
			)
		)
		(property "Value" "SCD01U16V1KX-GP"
			(at 2.8321 -1.7399 270)
			(unlocked yes)
			(layer "B.Fab")
			(hide yes)
			(effects
				(font
					(size 1.016 1.016)
					(thickness 0.1524)
				)
				(justify mirror)
			)
		)
		(property "Device Type" "C0201H13"
			(at 2.8321 -3.2639 270)
			(unlocked yes)
			(layer "B.Fab")
			(hide yes)
			(effects
				(font
					(size 1.016 1.016)
					(thickness 0.1524)
				)
				(justify mirror)
			)
		)
		(duplicate_pad_numbers_are_jumpers no)
		(fp_rect
			(start 0.2794 0.6477)
			(end -0.2794 -0.6477)
			(stroke
				(width 0)
				(type default)
			)
			(fill no)
			(layer "B.CrtYd")
		)
		(fp_rect
			(start 0.2794 0.6477)
			(end -0.2794 -0.6477)
			(stroke
				(width 0)
				(type default)
			)
			(fill no)
			(layer "B.Fab")
		)
		(pad "1" smd custom
			(at 0 -0.2794 90)
			(size 0.0762 0.0762)
			(layers "B.Cu" "B.Mask" "B.Paste")
			(net "PHY_DPB_TO_SCC_2_DP")
			(options
				(clearance outline)
				(anchor circle)
			)
			(primitives
				(gr_poly
					(pts
						(arc
							(start 0.1524 0.127)
							(mid 0.137521 0.162921)
							(end 0.1016 0.1778)
						)
						(arc
							(start -0.1016 0.1778)
							(mid -0.137521 0.162921)
							(end -0.1524 0.127)
						)
						(arc
							(start -0.1524 -0.127)
							(mid -0.137521 -0.162921)
							(end -0.1016 -0.1778)
						)
						(arc
							(start 0.1016 -0.1778)
							(mid 0.137521 -0.162921)
							(end 0.1524 -0.127)
						)
					)
					(width 0)
					(fill yes)
				)
			)
		)
		(pad "2" smd custom
			(at 0 0.2794 90)
			(size 0.0762 0.0762)
			(layers "B.Cu" "B.Mask" "B.Paste")
			(net "PHY_DPB_TO_SCC_C_2_DP")
			(options
				(clearance outline)
				(anchor circle)
			)
			(primitives
				(gr_poly
					(pts
						(arc
							(start 0.1524 0.127)
							(mid 0.137521 0.162921)
							(end 0.1016 0.1778)
						)
						(arc
							(start -0.1016 0.1778)
							(mid -0.137521 0.162921)
							(end -0.1524 0.127)
						)
						(arc
							(start -0.1524 -0.127)
							(mid -0.137521 -0.162921)
							(end -0.1016 -0.1778)
						)
						(arc
							(start 0.1016 -0.1778)
							(mid 0.137521 -0.162921)
							(end 0.1524 -0.127)
						)
					)
					(width 0)
					(fill yes)
				)
			)
		)
	)
	(footprint ""
		(layer "B.Cu")
		(at 73.66 -41.148 180)
		(property "Reference" "C305"
			(at 0 0 0)
			(layer "B.SilkS")
			(hide yes)
			(effects
				(font
					(size 1.27 1.27)
				)
				(justify mirror)
			)
		)
		(property "Value" "SC100U6D3V6MX-GP"
			(at 0.0762 -5.1308 180)
			(unlocked yes)
			(layer "B.Fab")
			(hide yes)
			(effects
				(font
					(size 1.016 1.016)
					(thickness 0.1524)
				)
				(justify mirror)
			)
		)
		(property "Device Type" "C1206H71"
			(at 0.127 -6.6548 180)
			(unlocked yes)
			(layer "B.Fab")
			(hide yes)
			(effects
				(font
					(size 1.016 1.016)
					(thickness 0.1524)
				)
				(justify mirror)
			)
		)
		(duplicate_pad_numbers_are_jumpers no)
		(fp_line
			(start 1.016 2.2352)
			(end 1.016 0.8382)
			(stroke
				(width 0.1524)
				(type default)
			)
			(layer "B.SilkS")
		)
		(fp_line
			(start 1.016 -0.8382)
			(end 1.016 -2.2352)
			(stroke
				(width 0.1524)
				(type default)
			)
			(layer "B.SilkS")
		)
		(fp_line
			(start 1.016 -2.2352)
			(end -1.016 -2.2352)
			(stroke
				(width 0.1524)
				(type default)
			)
			(layer "B.SilkS")
		)
		(fp_line
			(start -1.016 2.2352)
			(end 1.016 2.2352)
			(stroke
				(width 0.1524)
				(type default)
			)
			(layer "B.SilkS")
		)
		(fp_line
			(start -1.016 0.8382)
			(end -1.016 2.2352)
			(stroke
				(width 0.1524)
				(type default)
			)
			(layer "B.SilkS")
		)
		(fp_line
			(start -1.016 -2.2352)
			(end -1.016 -0.8382)
			(stroke
				(width 0.1524)
				(type default)
			)
			(layer "B.SilkS")
		)
		(fp_rect
			(start 1.0922 2.3114)
			(end -1.0922 -2.3114)
			(stroke
				(width 0)
				(type default)
			)
			(fill no)
			(layer "B.CrtYd")
		)
		(fp_poly
			(pts
				(xy -1.0922 -2.3114) (xy -1.0922 2.3114) (xy 1.0922 2.3114) (xy 1.0922 -2.3114)
			)
			(stroke
				(width 0)
				(type default)
			)
			(fill no)
			(layer "B.Fab")
		)
		(pad "1" smd rect
			(at 0 -1.397)
			(size 1.651 1.27)
			(layers "B.Cu" "B.Mask" "B.Paste")
			(net "GB_VDDA")
		)
		(pad "2" smd rect
			(at 0 1.397)
			(size 1.651 1.27)
			(layers "B.Cu" "B.Mask" "B.Paste")
			(net "GND")
		)
	)
	(footprint ""
		(layer "B.Cu")
		(at 166.751 -61.976 90)
		(property "Reference" "C352"
			(at 0 0 90)
			(layer "B.SilkS")
			(hide yes)
			(effects
				(font
					(size 1.27 1.27)
				)
				(justify mirror)
			)
		)
		(property "Value" "SC10U6D3V5KX-4GP"
			(at 0.0762 -6.1214 90)
			(unlocked yes)
			(layer "B.Fab")
			(hide yes)
			(effects
				(font
					(size 1.016 1.016)
					(thickness 0.1524)
				)
				(justify mirror)
			)
		)
		(property "Device Type" "C805H58"
			(at 0.0762 -8.1534 90)
			(unlocked yes)
			(layer "B.Fab")
			(hide yes)
			(effects
				(font
					(size 1.016 1.016)
					(thickness 0.1524)
				)
				(justify mirror)
			)
		)
		(duplicate_pad_numbers_are_jumpers no)
		(fp_line
			(start -0.635 0)
			(end 0.635 0)
			(stroke
				(width 0.508)
				(type default)
			)
			(layer "B.SilkS")
		)
		(fp_rect
			(start 0.9652 1.778)
			(end -0.9652 -1.778)
			(stroke
				(width 0)
				(type default)
			)
			(fill no)
			(layer "B.CrtYd")
		)
		(fp_poly
			(pts
				(xy 0.9652 -1.778) (xy -0.9652 -1.778) (xy -0.9652 1.778) (xy 0.9652 1.778)
			)
			(stroke
				(width 0)
				(type default)
			)
			(fill no)
			(layer "B.Fab")
		)
		(pad "1" smd rect
			(at 0 -0.9652 270)
			(size 1.397 1.143)
			(layers "B.Cu" "B.Mask" "B.Paste")
			(net "HM40ADC_VDDA")
		)
		(pad "2" smd rect
			(at 0 0.9652 270)
			(size 1.397 1.143)
			(layers "B.Cu" "B.Mask" "B.Paste")
			(net "GND")
		)
	)
	(footprint ""
		(layer "B.Cu")
		(at 136.2456 -80.5688 -90)
		(property "Reference" "C1"
			(at 0 0 90)
			(layer "B.SilkS")
			(hide yes)
			(effects
				(font
					(size 1.27 1.27)
				)
				(justify mirror)
			)
		)
		(property "Value" "SCD01U16V1KX-GP"
			(at 2.8321 -1.7399 270)
			(unlocked yes)
			(layer "B.Fab")
			(hide yes)
			(effects
				(font
					(size 1.016 1.016)
					(thickness 0.1524)
				)
				(justify mirror)
			)
		)
		(property "Device Type" "C0201H13"
			(at 2.8321 -3.2639 270)
			(unlocked yes)
			(layer "B.Fab")
			(hide yes)
			(effects
				(font
					(size 1.016 1.016)
					(thickness 0.1524)
				)
				(justify mirror)
			)
		)
		(duplicate_pad_numbers_are_jumpers no)
		(fp_rect
			(start 0.2794 0.6477)
			(end -0.2794 -0.6477)
			(stroke
				(width 0)
				(type default)
			)
			(fill no)
			(layer "B.CrtYd")
		)
		(fp_rect
			(start 0.2794 0.6477)
			(end -0.2794 -0.6477)
			(stroke
				(width 0)
				(type default)
			)
			(fill no)
			(layer "B.Fab")
		)
		(pad "1" smd custom
			(at 0 -0.2794 90)
			(size 0.0762 0.0762)
			(layers "B.Cu" "B.Mask" "B.Paste")
			(net "PHY_CONN_TO_EXP_11_DP")
			(options
				(clearance outline)
				(anchor circle)
			)
			(primitives
				(gr_poly
					(pts
						(arc
							(start 0.1524 0.127)
							(mid 0.137521 0.162921)
							(end 0.1016 0.1778)
						)
						(arc
							(start -0.1016 0.1778)
							(mid -0.137521 0.162921)
							(end -0.1524 0.127)
						)
						(arc
							(start -0.1524 -0.127)
							(mid -0.137521 -0.162921)
							(end -0.1016 -0.1778)
						)
						(arc
							(start 0.1016 -0.1778)
							(mid 0.137521 -0.162921)
							(end 0.1524 -0.127)
						)
					)
					(width 0)
					(fill yes)
				)
			)
		)
		(pad "2" smd custom
			(at 0 0.2794 90)
			(size 0.0762 0.0762)
			(layers "B.Cu" "B.Mask" "B.Paste")
			(net "PHY_CONN_TO_EXP_C_11_DP")
			(options
				(clearance outline)
				(anchor circle)
			)
			(primitives
				(gr_poly
					(pts
						(arc
							(start 0.1524 0.127)
							(mid 0.137521 0.162921)
							(end 0.1016 0.1778)
						)
						(arc
							(start -0.1016 0.1778)
							(mid -0.137521 0.162921)
							(end -0.1524 0.127)
						)
						(arc
							(start -0.1524 -0.127)
							(mid -0.137521 -0.162921)
							(end -0.1016 -0.1778)
						)
						(arc
							(start 0.1016 -0.1778)
							(mid 0.137521 -0.162921)
							(end 0.1524 -0.127)
						)
					)
					(width 0)
					(fill yes)
				)
			)
		)
	)
	(footprint ""
		(layer "B.Cu")
		(at 136.1948 -89.6874)
		(property "Reference" "R56"
			(at 0 0 0)
			(layer "B.SilkS")
			(hide yes)
			(effects
				(font
					(size 1.27 1.27)
				)
				(justify mirror)
			)
		)
		(property "Value" "4K7R2F-GP"
			(at -0.064008 -3.993896 0)
			(unlocked yes)
			(layer "B.Fab")
			(hide yes)
			(effects
				(font
					(size 1.016 1.016)
					(thickness 0.1524)
				)
				(justify mirror)
			)
		)
		(property "Device Type" "R402H16"
			(at -0.064008 -5.517896 0)
			(unlocked yes)
			(layer "B.Fab")
			(hide yes)
			(effects
				(font
					(size 1.016 1.016)
					(thickness 0.1524)
				)
				(justify mirror)
			)
		)
		(duplicate_pad_numbers_are_jumpers no)
		(fp_line
			(start -0.508 -0.9398)
			(end 0.508 -0.9398)
			(stroke
				(width 0.1524)
				(type default)
			)
			(layer "B.SilkS")
		)
		(fp_line
			(start 0.508 -0.9398)
			(end 0.508 0.9398)
			(stroke
				(width 0.1524)
				(type default)
			)
			(layer "B.SilkS")
		)
		(fp_rect
			(start 0.508 0.9398)
			(end -0.508 -0.9398)
			(stroke
				(width 0)
				(type default)
			)
			(fill no)
			(layer "B.CrtYd")
		)
		(fp_rect
			(start 0.508 0.9398)
			(end -0.508 -0.9398)
			(stroke
				(width 0)
				(type default)
			)
			(fill no)
			(layer "B.Fab")
		)
		(pad "1" smd custom
			(at 0 -0.4445 180)
			(size 0.1397 0.1397)
			(layers "B.Cu" "B.Mask" "B.Paste")
			(net "P1V8_E")
			(options
				(clearance outline)
				(anchor circle)
			)
			(primitives
				(gr_poly
					(pts
						(arc
							(start -0.1778 0.2794)
							(mid -0.249642 0.249642)
							(end -0.2794 0.1778)
						)
						(arc
							(start -0.2794 -0.1778)
							(mid -0.249642 -0.249642)
							(end -0.1778 -0.2794)
						)
						(arc
							(start 0.1778 -0.2794)
							(mid 0.249642 -0.249642)
							(end 0.2794 -0.1778)
						)
						(arc
							(start 0.2794 0.1778)
							(mid 0.249642 0.249642)
							(end 0.1778 0.2794)
						)
					)
					(width 0)
					(fill yes)
				)
			)
		)
		(pad "2" smd custom
			(at 0 0.4445 180)
			(size 0.1397 0.1397)
			(layers "B.Cu" "B.Mask" "B.Paste")
			(net "I2C_DRIVE_PWR_SCL4_LS")
			(options
				(clearance outline)
				(anchor circle)
			)
			(primitives
				(gr_poly
					(pts
						(arc
							(start -0.1778 0.2794)
							(mid -0.249642 0.249642)
							(end -0.2794 0.1778)
						)
						(arc
							(start -0.2794 -0.1778)
							(mid -0.249642 -0.249642)
							(end -0.1778 -0.2794)
						)
						(arc
							(start 0.1778 -0.2794)
							(mid 0.249642 -0.249642)
							(end 0.2794 -0.1778)
						)
						(arc
							(start 0.2794 0.1778)
							(mid 0.249642 0.249642)
							(end 0.1778 0.2794)
						)
					)
					(width 0)
					(fill yes)
				)
			)
		)
	)
	(footprint ""
		(layer "B.Cu")
		(at 91.007692 -64.044576 180)
		(property "Reference" "R151"
			(at 0 0 0)
			(layer "B.SilkS")
			(hide yes)
			(effects
				(font
					(size 1.27 1.27)
				)
				(justify mirror)
			)
		)
		(property "Value" "10R2F-L-GP"
			(at -0.064008 -3.993896 180)
			(unlocked yes)
			(layer "B.Fab")
			(hide yes)
			(effects
				(font
					(size 1.016 1.016)
					(thickness 0.1524)
				)
				(justify mirror)
			)
		)
		(property "Device Type" "R402H14"
			(at -0.064008 -5.517896 180)
			(unlocked yes)
			(layer "B.Fab")
			(hide yes)
			(effects
				(font
					(size 1.016 1.016)
					(thickness 0.1524)
				)
				(justify mirror)
			)
		)
		(duplicate_pad_numbers_are_jumpers no)
		(fp_line
			(start 0.508 -0.9398)
			(end 0.508 0.9398)
			(stroke
				(width 0.1524)
				(type default)
			)
			(layer "B.SilkS")
		)
		(fp_line
			(start -0.508 -0.9398)
			(end 0.508 -0.9398)
			(stroke
				(width 0.1524)
				(type default)
			)
			(layer "B.SilkS")
		)
		(fp_rect
			(start 0.508 0.9398)
			(end -0.508 -0.9398)
			(stroke
				(width 0)
				(type default)
			)
			(fill no)
			(layer "B.CrtYd")
		)
		(fp_rect
			(start 0.508 0.9398)
			(end -0.508 -0.9398)
			(stroke
				(width 0)
				(type default)
			)
			(fill no)
			(layer "B.Fab")
		)
		(pad "1" smd custom
			(at 0 -0.4445)
			(size 0.1397 0.1397)
			(layers "B.Cu" "B.Mask" "B.Paste")
			(net "P1V8_E")
			(options
				(clearance outline)
				(anchor circle)
			)
			(primitives
				(gr_poly
					(pts
						(arc
							(start -0.1778 0.2794)
							(mid -0.249642 0.249642)
							(end -0.2794 0.1778)
						)
						(arc
							(start -0.2794 -0.1778)
							(mid -0.249642 -0.249642)
							(end -0.1778 -0.2794)
						)
						(arc
							(start 0.1778 -0.2794)
							(mid 0.249642 -0.249642)
							(end 0.2794 -0.1778)
						)
						(arc
							(start 0.2794 0.1778)
							(mid 0.249642 0.249642)
							(end 0.1778 0.2794)
						)
					)
					(width 0)
					(fill yes)
				)
			)
		)
		(pad "2" smd custom
			(at 0 0.4445)
			(size 0.1397 0.1397)
			(layers "B.Cu" "B.Mask" "B.Paste")
			(net "XTAL_VDDA18")
			(options
				(clearance outline)
				(anchor circle)
			)
			(primitives
				(gr_poly
					(pts
						(arc
							(start -0.1778 0.2794)
							(mid -0.249642 0.249642)
							(end -0.2794 0.1778)
						)
						(arc
							(start -0.2794 -0.1778)
							(mid -0.249642 -0.249642)
							(end -0.1778 -0.2794)
						)
						(arc
							(start 0.1778 -0.2794)
							(mid 0.249642 -0.249642)
							(end 0.2794 -0.1778)
						)
						(arc
							(start 0.2794 0.1778)
							(mid 0.249642 0.249642)
							(end 0.1778 0.2794)
						)
					)
					(width 0)
					(fill yes)
				)
			)
		)
	)
	(footprint ""
		(layer "B.Cu")
		(at 119.50446 -71.9582)
		(property "Reference" "C123"
			(at 0 0 0)
			(layer "B.SilkS")
			(hide yes)
			(effects
				(font
					(size 1.27 1.27)
				)
				(justify mirror)
			)
		)
		(property "Value" "SC1KP25V1KX-GP"
			(at 2.8321 -1.7399 0)
			(unlocked yes)
			(layer "B.Fab")
			(hide yes)
			(effects
				(font
					(size 1.016 1.016)
					(thickness 0.1524)
				)
				(justify mirror)
			)
		)
		(property "Device Type" "C0201H13"
			(at 2.8321 -3.2639 0)
			(unlocked yes)
			(layer "B.Fab")
			(hide yes)
			(effects
				(font
					(size 1.016 1.016)
					(thickness 0.1524)
				)
				(justify mirror)
			)
		)
		(duplicate_pad_numbers_are_jumpers no)
		(fp_rect
			(start 0.2794 0.6477)
			(end -0.2794 -0.6477)
			(stroke
				(width 0)
				(type default)
			)
			(fill no)
			(layer "B.CrtYd")
		)
		(fp_rect
			(start 0.2794 0.6477)
			(end -0.2794 -0.6477)
			(stroke
				(width 0)
				(type default)
			)
			(fill no)
			(layer "B.Fab")
		)
		(pad "1" smd custom
			(at 0 -0.2794 180)
			(size 0.0762 0.0762)
			(layers "B.Cu" "B.Mask" "B.Paste")
			(net "P1V8_E")
			(options
				(clearance outline)
				(anchor circle)
			)
			(primitives
				(gr_poly
					(pts
						(arc
							(start 0.1524 0.127)
							(mid 0.137521 0.162921)
							(end 0.1016 0.1778)
						)
						(arc
							(start -0.1016 0.1778)
							(mid -0.137521 0.162921)
							(end -0.1524 0.127)
						)
						(arc
							(start -0.1524 -0.127)
							(mid -0.137521 -0.162921)
							(end -0.1016 -0.1778)
						)
						(arc
							(start 0.1016 -0.1778)
							(mid 0.137521 -0.162921)
							(end 0.1524 -0.127)
						)
					)
					(width 0)
					(fill yes)
				)
			)
		)
		(pad "2" smd custom
			(at 0 0.2794 180)
			(size 0.0762 0.0762)
			(layers "B.Cu" "B.Mask" "B.Paste")
			(net "GND")
			(options
				(clearance outline)
				(anchor circle)
			)
			(primitives
				(gr_poly
					(pts
						(arc
							(start 0.1524 0.127)
							(mid 0.137521 0.162921)
							(end 0.1016 0.1778)
						)
						(arc
							(start -0.1016 0.1778)
							(mid -0.137521 0.162921)
							(end -0.1524 0.127)
						)
						(arc
							(start -0.1524 -0.127)
							(mid -0.137521 -0.162921)
							(end -0.1016 -0.1778)
						)
						(arc
							(start 0.1016 -0.1778)
							(mid 0.137521 -0.162921)
							(end 0.1524 -0.127)
						)
					)
					(width 0)
					(fill yes)
				)
			)
		)
	)
)
